FILE_TYPE = MACRO_DRAWING;
SET COLOR_WIRE YELLOW;
SET COLOR_PROP ORANGE;
SET COLOR_DOT WHITE;
SET COLOR_ARC YELLOW;
SET COLOR_BODY GREEN;
SET COLOR_NOTE PURPLE;
SET PROP_DISPLAY VALUE;
SET PAGE_NUMBER P178;
FORCEADD UNIVERSAL_POWER..1
(5300 1625);
FORCEPROP 3 LASTPIN (5300 1575) SIG_NAME P3V3_RTC_AUX\g
J 0
(5310 1585);
DISPLAY 0.659574 (5310 1585);
PAINT MONO (5310 1585);
DISPLAY INVISIBLE (5310 1585);
FORCEPROP 1 LAST HDL_POWER P3V3_RTC_AUX
J 1
(5300 1675);
DISPLAY 0.872340 (5300 1675);
PAINT GREEN (5300 1675);
FORCEPROP 2 LAST CDS_LIB logical_power
J 0
(5300 1625);
PAINT MONO (5300 1625);
DISPLAY INVISIBLE (5300 1625);
FORCEPROP 1 LAST PATH I10
J 0
(5350 1650);
DISPLAY 0.872340 (5350 1650);
PAINT AQUA (5350 1650);
DISPLAY INVISIBLE (5350 1650);
FORCEADD EMMITSBURG_REV0P9..8
(1875 2250);
FORCEPROP 1 LAST PART_NUMBER AJ0QV2N0T00
J 0
(382 3622);
DISPLAY 0.723404 (382 3622);
PAINT GREEN (382 3622);
DISPLAY INVISIBLE (382 3622);
FORCEPROP 2 LAST PART_TYPE SMLF
J 0
(400 3875);
DISPLAY 1.021277 (400 3875);
FORCEPROP 2 LAST VALUE GFNOCPU04302300-QV2N-MM#99A1WT
J 0
(400 3825);
DISPLAY 1.021277 (400 3825);
FORCEPROP 1 LAST MATERIAL IC
J 0
(382 3495);
DISPLAY 0.723404 (382 3495);
PAINT GREEN (382 3495);
FORCEPROP 1 LAST $LOCATION U4
J 0
(382 3769);
DISPLAY 0.723404 (382 3769);
PAINT GREEN (382 3769);
FORCEPROP 2 LASTPIN (225 1275) $PN AF15
J 2
(215 1285);
DISPLAY 0.808511 (215 1285);
FORCEPROP 2 LASTPIN (225 1225) $PN AN26
J 2
(215 1235);
DISPLAY 0.808511 (215 1235);
FORCEPROP 2 LASTPIN (225 2425) $PN AB19
J 2
(215 2435);
DISPLAY 0.808511 (215 2435);
FORCEPROP 2 LASTPIN (225 2475) $PN AB20
J 2
(215 2485);
DISPLAY 0.808511 (215 2485);
FORCEPROP 2 LASTPIN (225 2525) $PN AB22
J 2
(215 2535);
DISPLAY 0.808511 (215 2535);
FORCEPROP 2 LASTPIN (225 2575) $PN AB24
J 2
(215 2585);
DISPLAY 0.808511 (215 2585);
FORCEPROP 2 LASTPIN (225 2875) $PN AD25
J 2
(215 2885);
DISPLAY 0.808511 (215 2885);
FORCEPROP 2 LASTPIN (225 2925) $PN AD27
J 2
(215 2935);
DISPLAY 0.808511 (215 2935);
FORCEPROP 2 LASTPIN (225 2975) $PN AF25
J 2
(215 2985);
DISPLAY 0.808511 (215 2985);
FORCEPROP 2 LASTPIN (225 3025) $PN AF27
J 2
(215 3035);
DISPLAY 0.808511 (215 3035);
FORCEPROP 2 LASTPIN (225 3075) $PN AG25
J 2
(215 3085);
DISPLAY 0.808511 (215 3085);
FORCEPROP 2 LASTPIN (225 3125) $PN AG27
J 2
(215 3135);
DISPLAY 0.808511 (215 3135);
FORCEPROP 2 LASTPIN (225 3175) $PN AJ25
J 2
(215 3185);
DISPLAY 0.808511 (215 3185);
FORCEPROP 2 LASTPIN (225 3225) $PN AJ27
J 2
(215 3235);
DISPLAY 0.808511 (215 3235);
FORCEPROP 2 LASTPIN (225 3325) $PN AR26
J 2
(215 3335);
DISPLAY 0.808511 (215 3335);
FORCEPROP 2 LASTPIN (225 1575) $PN AA29
J 2
(215 1585);
DISPLAY 0.808511 (215 1585);
FORCEPROP 2 LASTPIN (225 1925) $PN AB27
J 2
(215 1935);
DISPLAY 0.808511 (215 1935);
FORCEPROP 2 LASTPIN (225 1375) $PN AE29
J 2
(215 1385);
DISPLAY 0.808511 (215 1385);
FORCEPROP 2 LASTPIN (225 1425) $PN AG29
J 2
(215 1435);
DISPLAY 0.808511 (215 1435);
FORCEPROP 2 LASTPIN (225 1475) $PN AL25
J 2
(215 1485);
DISPLAY 0.808511 (215 1485);
FORCEPROP 2 LASTPIN (225 1775) $PN R23
J 2
(215 1785);
DISPLAY 0.808511 (215 1785);
FORCEPROP 2 LASTPIN (225 1825) $PN R26
J 2
(215 1835);
DISPLAY 0.808511 (215 1835);
FORCEPROP 2 LASTPIN (225 1675) $PN R29
J 2
(215 1685);
DISPLAY 0.808511 (215 1685);
FORCEPROP 2 LASTPIN (225 1625) $PN U27
J 2
(215 1635);
DISPLAY 0.808511 (215 1635);
FORCEPROP 2 LASTPIN (225 2675) $PN M24
J 2
(215 2685);
DISPLAY 0.808511 (215 2685);
FORCEPROP 2 LASTPIN (225 2775) $PN N23
J 2
(215 2785);
DISPLAY 0.808511 (215 2785);
FORCEPROP 2 LASTPIN (225 2725) $PN N26
J 2
(215 2735);
DISPLAY 0.808511 (215 2735);
FORCEPROP 2 LASTPIN (225 2025) $PN P15
J 2
(215 2035);
DISPLAY 0.808511 (215 2035);
FORCEPROP 2 LASTPIN (225 2125) $PN W17
J 2
(215 2135);
DISPLAY 0.808511 (215 2135);
FORCEPROP 2 LASTPIN (225 2175) $PN W19
J 2
(215 2185);
DISPLAY 0.808511 (215 2185);
FORCEPROP 2 LASTPIN (225 2225) $PN W20
J 2
(215 2235);
DISPLAY 0.808511 (215 2235);
FORCEPROP 2 LASTPIN (225 2275) $PN W22
J 2
(215 2285);
DISPLAY 0.808511 (215 2285);
FORCEPROP 2 LASTPIN (225 2325) $PN W24
J 2
(215 2335);
DISPLAY 0.808511 (215 2335);
FORCEPROP 2 LASTPIN (3525 2725) $PN AB31
J 0
(3535 2735);
DISPLAY 0.808511 (3535 2735);
FORCEPROP 2 LASTPIN (3525 2525) $PN AB34
J 0
(3535 2535);
DISPLAY 0.808511 (3535 2535);
FORCEPROP 2 LASTPIN (3525 2625) $PN U29
J 0
(3535 2635);
DISPLAY 0.808511 (3535 2635);
FORCEPROP 2 LASTPIN (3525 2675) $PN W27
J 0
(3535 2685);
DISPLAY 0.808511 (3535 2685);
FORCEPROP 2 LASTPIN (3525 2575) $PN W29
J 0
(3535 2585);
DISPLAY 0.808511 (3535 2585);
FORCEPROP 2 LASTPIN (3525 2175) $PN N20
J 0
(3535 2185);
DISPLAY 0.808511 (3535 2185);
FORCEPROP 2 LASTPIN (3525 2225) $PN U17
J 0
(3535 2235);
DISPLAY 0.808511 (3535 2235);
FORCEPROP 2 LASTPIN (3525 2275) $PN U19
J 0
(3535 2285);
DISPLAY 0.808511 (3535 2285);
FORCEPROP 2 LASTPIN (3525 2325) $PN U20
J 0
(3535 2335);
DISPLAY 0.808511 (3535 2335);
FORCEPROP 2 LASTPIN (3525 2375) $PN U22
J 0
(3535 2385);
DISPLAY 0.808511 (3535 2385);
FORCEPROP 2 LASTPIN (3525 2425) $PN U24
J 0
(3535 2435);
DISPLAY 0.808511 (3535 2435);
FORCEPROP 2 LASTPIN (3525 1725) $PN AF17
J 0
(3535 1735);
DISPLAY 0.808511 (3535 1735);
FORCEPROP 2 LASTPIN (3525 1775) $PN AG17
J 0
(3535 1785);
DISPLAY 0.808511 (3535 1785);
FORCEPROP 2 LASTPIN (3525 1825) $PN AJ17
J 0
(3535 1835);
DISPLAY 0.808511 (3535 1835);
FORCEPROP 2 LASTPIN (3525 1675) $PN AK15
J 0
(3535 1685);
DISPLAY 0.808511 (3535 1685);
FORCEPROP 2 LASTPIN (3525 1875) $PN AL17
J 0
(3535 1885);
DISPLAY 0.808511 (3535 1885);
FORCEPROP 2 LASTPIN (3525 1475) $PN AD15
J 0
(3535 1485);
DISPLAY 0.808511 (3535 1485);
FORCEPROP 2 LASTPIN (3525 1525) $PN V15
J 0
(3535 1535);
DISPLAY 0.808511 (3535 1535);
FORCEPROP 2 LASTPIN (3525 1625) $PN P21
J 0
(3535 1635);
DISPLAY 0.808511 (3535 1635);
FORCEPROP 2 LASTPIN (3525 2075) $PN T15
J 0
(3535 2085);
DISPLAY 0.808511 (3535 2085);
FORCEPROP 2 LASTPIN (3525 2025) $PN AN20
J 0
(3535 2035);
DISPLAY 0.808511 (3535 2035);
FORCEPROP 2 LASTPIN (3525 1975) $PN AD17
J 0
(3535 1985);
DISPLAY 0.808511 (3535 1985);
FORCEPROP 2 LASTPIN (3525 2825) $PN AF20
J 0
(3535 2835);
DISPLAY 0.808511 (3535 2835);
FORCEPROP 2 LASTPIN (3525 2875) $PN AF22
J 0
(3535 2885);
DISPLAY 0.808511 (3535 2885);
FORCEPROP 2 LASTPIN (3525 2925) $PN AG20
J 0
(3535 2935);
DISPLAY 0.808511 (3535 2935);
FORCEPROP 2 LASTPIN (3525 2975) $PN AG22
J 0
(3535 2985);
DISPLAY 0.808511 (3535 2985);
FORCEPROP 2 LASTPIN (3525 3025) $PN AJ20
J 0
(3535 3035);
DISPLAY 0.808511 (3535 3035);
FORCEPROP 2 LASTPIN (3525 3075) $PN AJ22
J 0
(3535 3085);
DISPLAY 0.808511 (3535 3085);
FORCEPROP 2 LASTPIN (3525 3125) $PN AL20
J 0
(3535 3135);
DISPLAY 0.808511 (3535 3135);
FORCEPROP 2 LASTPIN (3525 3175) $PN AL22
J 0
(3535 3185);
DISPLAY 0.808511 (3535 3185);
FORCEPROP 2 LASTPIN (3525 3225) $PN AN23
J 0
(3535 3235);
DISPLAY 0.808511 (3535 3235);
FORCEPROP 2 LASTPIN (3525 3275) $PN AP21
J 0
(3535 3285);
DISPLAY 0.808511 (3535 3285);
FORCEPROP 2 LASTPIN (3525 3325) $PN AR23
J 0
(3535 3335);
DISPLAY 0.808511 (3535 3335);
FORCEPROP 2 LASTPIN (3525 1375) $PN AH15
J 0
(3535 1385);
DISPLAY 0.808511 (3535 1385);
FORCEPROP 2 LASTPIN (225 1175) $PN BG40
J 2
(215 1185);
DISPLAY 0.808511 (215 1185);
FORCEPROP 2 LAST CDS_LIB pure_quanta
J 0
(1875 2250);
PAINT MONO (1875 2250);
DISPLAY INVISIBLE (1875 2250);
FORCEPROP 1 LAST CDS_LMAN_SYM_OUTLINE -1500,1225,1500,-1225
J 0
(1875 2250);
DISPLAY 0.468085 (1875 2250);
PAINT GREEN (1875 2250);
DISPLAY INVISIBLE (1875 2250);
FORCEPROP 1 LAST NEEDS_NO_SIZE TRUE
J 0
(1875 2250);
DISPLAY 0.723404 (1875 2250);
PAINT GREEN (1875 2250);
DISPLAY INVISIBLE (1875 2250);
FORCEPROP 1 LAST PATH I11
J 0
(1875 2250);
DISPLAY 0.723404 (1875 2250);
PAINT GREEN (1875 2250);
DISPLAY INVISIBLE (1875 2250);
FORCEPROP 2 LAST CDS_LOCATION U4
J 0
(375 3650);
DISPLAY 1.021277 (375 3650);
DISPLAY INVISIBLE (375 3650);
FORCEPROP 2 LAST $SEC 8
J 0
(400 3925);
DISPLAY 0.680851 (400 3925);
PAINT MONO (400 3925);
DISPLAY INVISIBLE (400 3925);
FORCEPROP 2 LAST CDS_SEC 8
J 0
(375 3650);
DISPLAY 1.021277 (375 3650);
DISPLAY INVISIBLE (375 3650);
FORCEADD UNIVERSAL_POWER..1
(-600 2150);
FORCEPROP 3 LASTPIN (-600 2100) SIG_NAME P1V05_PCH_PLL_AUX\g
J 0
(-590 2110);
DISPLAY 0.659574 (-590 2110);
PAINT MONO (-590 2110);
DISPLAY INVISIBLE (-590 2110);
FORCEPROP 1 LAST HDL_POWER P1V05_PCH_PLL_AUX
J 1
(-600 2200);
DISPLAY 0.872340 (-600 2200);
PAINT GREEN (-600 2200);
FORCEPROP 2 LAST CDS_LIB logical_power
J 0
(-600 2150);
PAINT MONO (-600 2150);
DISPLAY INVISIBLE (-600 2150);
FORCEPROP 1 LAST PATH I17
J 0
(-550 2175);
DISPLAY 0.872340 (-550 2175);
PAINT AQUA (-550 2175);
DISPLAY INVISIBLE (-550 2175);
FORCEADD UNIVERSAL_GND..1
(-50 825);
FORCEPROP 3 LASTPIN (-50 875) SIG_NAME GND\g
J 0
(-40 885);
DISPLAY 0.659574 (-40 885);
PAINT MONO (-40 885);
DISPLAY INVISIBLE (-40 885);
FORCEPROP 2 LAST CDS_LIB logical_power
J 0
(-50 825);
DISPLAY INVISIBLE (-50 825);
FORCEPROP 1 LAST HDL_POWER GND
J 1
(-25 750);
DISPLAY 0.872340 (-25 750);
PAINT GREEN (-25 750);
DISPLAY INVISIBLE (-25 750);
FORCEPROP 1 LAST PATH I18
J 0
(25 825);
DISPLAY 0.872340 (25 825);
PAINT AQUA (25 825);
DISPLAY INVISIBLE (25 825);
FORCEPROP 2 LAST ROOM IO_SLOT
J 1
(-275 900);
DISPLAY 0.744681 (-275 900);
DISPLAY INVISIBLE (-275 900);
FORCEADD UNIVERSAL_POWER..1
(-75 3575);
FORCEPROP 3 LASTPIN (-75 3525) SIG_NAME P1V05_PCH_AUX\g
J 0
(-65 3535);
DISPLAY 0.659574 (-65 3535);
PAINT MONO (-65 3535);
DISPLAY INVISIBLE (-65 3535);
FORCEPROP 1 LAST HDL_POWER P1V05_PCH_AUX
J 1
(-75 3625);
DISPLAY 0.872340 (-75 3625);
PAINT GREEN (-75 3625);
FORCEPROP 2 LAST CDS_LIB logical_power
J 0
(-75 3575);
DISPLAY INVISIBLE (-75 3575);
FORCEPROP 1 LAST PATH I2
J 0
(-25 3600);
DISPLAY 0.872340 (-25 3600);
PAINT AQUA (-25 3600);
DISPLAY INVISIBLE (-25 3600);
FORCEADD UNIVERSAL_POWER..1
(3775 3600);
FORCEPROP 3 LASTPIN (3775 3550) SIG_NAME P1V05_PCH_AUX\g
J 0
(3785 3560);
DISPLAY 0.659574 (3785 3560);
PAINT MONO (3785 3560);
DISPLAY INVISIBLE (3785 3560);
FORCEPROP 1 LAST HDL_POWER P1V05_PCH_AUX
J 1
(3775 3650);
DISPLAY 0.872340 (3775 3650);
PAINT GREEN (3775 3650);
FORCEPROP 2 LAST CDS_LIB logical_power
J 0
(3775 3600);
DISPLAY INVISIBLE (3775 3600);
FORCEPROP 1 LAST PATH I5
J 0
(3825 3625);
DISPLAY 0.872340 (3825 3625);
PAINT AQUA (3825 3625);
DISPLAY INVISIBLE (3825 3625);
FORCEADD UNIVERSAL_POWER..1
(4150 2975);
FORCEPROP 3 LASTPIN (4150 2925) SIG_NAME P1V8_PCH_PLL_AUX\g
J 0
(4160 2935);
DISPLAY 0.659574 (4160 2935);
PAINT MONO (4160 2935);
DISPLAY INVISIBLE (4160 2935);
FORCEPROP 1 LAST HDL_POWER P1V8_PCH_PLL_AUX
J 1
(4150 3025);
DISPLAY 0.872340 (4150 3025);
PAINT GREEN (4150 3025);
FORCEPROP 2 LAST CDS_LIB logical_power
J 0
(4150 2975);
PAINT MONO (4150 2975);
DISPLAY INVISIBLE (4150 2975);
FORCEPROP 1 LAST PATH I6
J 0
(4200 3000);
DISPLAY 0.872340 (4200 3000);
PAINT AQUA (4200 3000);
DISPLAY INVISIBLE (4200 3000);
FORCEADD UNIVERSAL_POWER..1
(4450 2675);
FORCEPROP 3 LASTPIN (4450 2625) SIG_NAME P1V8_PCH_AUX\g
J 0
(4460 2635);
DISPLAY 0.659574 (4460 2635);
PAINT MONO (4460 2635);
DISPLAY INVISIBLE (4460 2635);
FORCEPROP 1 LAST HDL_POWER P1V8_PCH_AUX
J 1
(4450 2725);
DISPLAY 0.872340 (4450 2725);
PAINT GREEN (4450 2725);
FORCEPROP 2 LAST CDS_LIB logical_power
J 0
(4450 2675);
PAINT MONO (4450 2675);
DISPLAY INVISIBLE (4450 2675);
FORCEPROP 1 LAST PATH I7
J 0
(4500 2700);
DISPLAY 0.872340 (4500 2700);
PAINT AQUA (4500 2700);
DISPLAY INVISIBLE (4500 2700);
FORCEADD UNIVERSAL_POWER..1
(4675 2325);
FORCEPROP 3 LASTPIN (4675 2275) SIG_NAME P3V3_AUX\g
J 0
(4685 2285);
DISPLAY 0.659574 (4685 2285);
PAINT MONO (4685 2285);
DISPLAY INVISIBLE (4685 2285);
FORCEPROP 1 LAST HDL_POWER P3V3_AUX
J 1
(4675 2375);
DISPLAY 0.872340 (4675 2375);
PAINT GREEN (4675 2375);
FORCEPROP 2 LAST CDS_LIB logical_power
J 0
(4675 2325);
PAINT MONO (4675 2325);
DISPLAY INVISIBLE (4675 2325);
FORCEPROP 1 LAST PATH I8
J 0
(4725 2350);
DISPLAY 0.872340 (4725 2350);
PAINT AQUA (4725 2350);
DISPLAY INVISIBLE (4725 2350);
FORCEADD UNIVERSAL_POWER..1
(5000 1775);
FORCEPROP 3 LASTPIN (5000 1725) SIG_NAME P3V3_AUX\g
J 0
(5010 1735);
DISPLAY 0.659574 (5010 1735);
PAINT MONO (5010 1735);
DISPLAY INVISIBLE (5010 1735);
FORCEPROP 1 LAST HDL_POWER P3V3_AUX
J 1
(5000 1825);
DISPLAY 0.872340 (5000 1825);
PAINT GREEN (5000 1825);
FORCEPROP 2 LAST CDS_LIB logical_power
J 0
(5000 1775);
PAINT MONO (5000 1775);
DISPLAY INVISIBLE (5000 1775);
FORCEPROP 1 LAST PATH I9
J 0
(5050 1800);
DISPLAY 0.872340 (5050 1800);
PAINT AQUA (5050 1800);
DISPLAY INVISIBLE (5050 1800);
FORCEADD QUANTA_TITLE_BLOCK_C..1
(6400 -1950);
FORCEPROP 0 LAST CDS_CON_LAST_MODIFIED Fri Aug 25 14:02:58 2023
J 0
(4515 -1935);
PAINT MONO (4515 -1935);
DISPLAY INVISIBLE (4515 -1935);
FORCEPROP 1 LAST CUSTOM_TXT_CDS <CON_LAST_MODIFIED>
J 0
(4515 -1935);
DISPLAY 0.978723 (4515 -1935);
FORCEPROP 2 LAST CUSTOM_TXT_CDS <XR_PAGE_TITLE>
J 0
(-1490 3300);
DISPLAY 0.638298 (-1490 3300);
PAINT PINK (-1490 3300);
DISPLAY INVISIBLE (-1490 3300);
FORCEPROP 2 LAST CUSTOM_TXT_CDS <Q_NUMBER>
J 0
(4997 -1847);
DISPLAY 1.212766 (4997 -1847);
FORCEPROP 1 LAST CUSTOM_TXT_CDS <NAME_2>
J 0
(3225 -1900);
FORCEPROP 1 LAST CUSTOM_TXT_CDS <NAME_1>
J 0
(3225 -1775);
FORCEPROP 1 LAST CUSTOM_TXT_CDS <Q_PROJ>
J 0
(4018 -1848);
DISPLAY 1.212766 (4018 -1848);
FORCEPROP 1 LAST CUSTOM_TXT_CDS <Q_REV>
J 0
(6216 -1847);
DISPLAY 1.212766 (6216 -1847);
FORCEPROP 1 LAST CUSTOM_TXT_CDS <CON_PAGE_NUM> OF <CON_TOTAL_PAGES>
J 0
(5954 -1932);
DISPLAY 0.978723 (5954 -1932);
FORCEPROP 1 LAST Q_TITLE EMMITSBURG - POWER (8/10)
J 0
(-2916 -1924);
DISPLAY 1.957447 (-2916 -1924);
PAINT GREEN (-2916 -1924);
FORCEPROP 1 LAST Q_DEPT 
J 1
(2637 -1901);
DISPLAY 1.957447 (2637 -1901);
PAINT GREEN (2637 -1901);
FORCEPROP 2 LAST CDS_XR_PAGE_TITLE CR-186 : @S9S_MB_2U_LIB.S9S_MB_2U(SCH_1):PAGE186
J 0
(-1490 3300);
DISPLAY 0.638298 (-1490 3300);
PAINT PINK (-1490 3300);
DISPLAY INVISIBLE (-1490 3300);
FORCEPROP 1 LAST COMMENT_BODY TRUE
J 0
(6412 -1963);
DISPLAY 0.978723 (6412 -1963);
PAINT GREEN (6412 -1963);
DISPLAY INVISIBLE (6412 -1963);
FORCEPROP 2 LAST CDS_LIB pure_quanta
J 0
(6400 -1950);
PAINT MONO (6400 -1950);
DISPLAY INVISIBLE (6400 -1950);
FORCEPROP 1 LAST CDS_LMAN_SYM_OUTLINE -9475,6775,100,-125
J 0
(6400 -1950);
DISPLAY 0.468085 (6400 -1950);
PAINT GREEN (6400 -1950);
DISPLAY INVISIBLE (6400 -1950);
FORCEPROP 2 LAST PAGE_BORDER TRUE
J 0
(-1490 3300);
DISPLAY 0.638298 (-1490 3300);
PAINT PINK (-1490 3300);
DISPLAY INVISIBLE (-1490 3300);
WIRE 16 -1 (5000 1725)(5000 1525);
WIRE 16 -1 (4675 2275)(4675 2075);
WIRE 16 -1 (4450 2625)(4450 2425);
WIRE 16 -1 (4150 2925)(4150 2725);
WIRE 16 -1 (3775 3550)(3775 3325);
WIRE 16 -1 (-75 3525)(-75 3325);
WIRE 16 -1 (-600 2100)(-600 1925);
WIRE 16 -1 (5300 1575)(5300 1375);
WIRE 16 -1 (-50 1175)(-50 875);
WIRE 16 -1 (-50 1175)(225 1175);
WIRE 16 -1 (-700 1275)(225 1275);
FORCEPROP 0 LAST CDS_PHYS_NET_NAME FM_PCH_SLP_S4_N
J 0
(-675 1317);
PAINT MONO (-675 1317);
DISPLAY INVISIBLE (-675 1317);
FORCEPROP 0 LAST SIG_NAME TP_PCH_RSVD<16>
J 0
(-600 1285);
DISPLAY 0.680851 (-600 1285);
PAINT WHITE (-600 1285);
WIRE 16 -1 (-600 1925)(-400 1925);
WIRE 16 -1 (-400 1925)(225 1925);
WIRE 16 -1 (-400 1825)(-400 1925);
WIRE 16 -1 (-400 1825)(225 1825);
WIRE 16 -1 (-400 1825)(-400 1775);
WIRE 16 -1 (-400 1775)(225 1775);
WIRE 16 -1 (-400 1775)(-400 1675);
WIRE 16 -1 (-400 1675)(225 1675);
WIRE 16 -1 (-400 1675)(-400 1625);
WIRE 16 -1 (-400 1625)(225 1625);
WIRE 16 -1 (-400 1625)(-400 1575);
WIRE 16 -1 (-400 1575)(225 1575);
WIRE 16 -1 (-400 1475)(-400 1575);
WIRE 16 -1 (-400 1475)(225 1475);
WIRE 16 -1 (-400 1475)(-400 1425);
WIRE 16 -1 (-400 1425)(225 1425);
WIRE 16 -1 (-400 1425)(-400 1375);
WIRE 16 -1 (-400 1375)(225 1375);
WIRE 16 -1 (-700 1225)(225 1225);
FORCEPROP 0 LAST CDS_PHYS_NET_NAME FM_PCH_SLP_S4_N
J 0
(-675 1267);
PAINT MONO (-675 1267);
DISPLAY INVISIBLE (-675 1267);
FORCEPROP 0 LAST SIG_NAME TP_PCH_RSVD<15>
J 0
(-600 1235);
DISPLAY 0.680851 (-600 1235);
PAINT WHITE (-600 1235);
WIRE 16 -1 (-75 2025)(225 2025);
WIRE 16 -1 (-75 2125)(-75 2025);
WIRE 16 -1 (-75 2125)(225 2125);
WIRE 16 -1 (-75 2125)(-75 2175);
WIRE 16 -1 (-75 2175)(225 2175);
WIRE 16 -1 (-75 2175)(-75 2225);
WIRE 16 -1 (-75 2225)(225 2225);
WIRE 16 -1 (-75 2275)(-75 2225);
WIRE 16 -1 (-75 2275)(225 2275);
WIRE 16 -1 (-75 2325)(-75 2275);
WIRE 16 -1 (-75 2325)(225 2325);
WIRE 16 -1 (-75 2325)(-75 2425);
WIRE 16 -1 (-75 2425)(225 2425);
WIRE 16 -1 (-75 2475)(-75 2425);
WIRE 16 -1 (-75 2475)(225 2475);
WIRE 16 -1 (-75 2525)(-75 2475);
WIRE 16 -1 (-75 2525)(225 2525);
WIRE 16 -1 (-75 2575)(-75 2525);
WIRE 16 -1 (-75 2575)(225 2575);
WIRE 16 -1 (-75 2675)(-75 2575);
WIRE 16 -1 (-75 2675)(225 2675);
WIRE 16 -1 (-75 2725)(-75 2675);
WIRE 16 -1 (-75 2725)(225 2725);
WIRE 16 -1 (-75 2775)(-75 2725);
WIRE 16 -1 (-75 2775)(225 2775);
WIRE 16 -1 (-75 2775)(-75 2875);
WIRE 16 -1 (-75 2875)(225 2875);
WIRE 16 -1 (-75 2925)(-75 2875);
WIRE 16 -1 (-75 2925)(225 2925);
WIRE 16 -1 (-75 2975)(-75 2925);
WIRE 16 -1 (-75 2975)(225 2975);
WIRE 16 -1 (-75 3025)(-75 2975);
WIRE 16 -1 (-75 3025)(225 3025);
WIRE 16 -1 (-75 3075)(-75 3025);
WIRE 16 -1 (-75 3075)(225 3075);
WIRE 16 -1 (-75 3125)(-75 3075);
WIRE 16 -1 (-75 3125)(225 3125);
WIRE 16 -1 (-75 3175)(-75 3125);
WIRE 16 -1 (-75 3175)(225 3175);
WIRE 16 -1 (-75 3225)(-75 3175);
WIRE 16 -1 (-75 3225)(225 3225);
WIRE 16 -1 (-75 3225)(-75 3325);
WIRE 16 -1 (-75 3325)(225 3325);
WIRE 16 -1 (3525 2175)(4450 2175);
WIRE 16 -1 (4450 2225)(3525 2225);
WIRE 16 -1 (4450 2225)(4450 2175);
WIRE 16 -1 (4450 2275)(3525 2275);
WIRE 16 -1 (4450 2275)(4450 2225);
WIRE 16 -1 (4450 2325)(3525 2325);
WIRE 16 -1 (4450 2325)(4450 2275);
WIRE 16 -1 (4450 2375)(3525 2375);
WIRE 16 -1 (4450 2375)(4450 2325);
WIRE 16 -1 (4450 2425)(3525 2425);
WIRE 16 -1 (4450 2425)(4450 2375);
WIRE 16 -1 (4150 2525)(3525 2525);
WIRE 16 -1 (4150 2575)(3525 2575);
WIRE 16 -1 (4150 2575)(4150 2525);
WIRE 16 -1 (4150 2625)(3525 2625);
WIRE 16 -1 (4150 2625)(4150 2575);
WIRE 16 -1 (3525 2675)(4150 2675);
WIRE 16 -1 (4150 2675)(4150 2625);
WIRE 16 -1 (4150 2725)(4150 2675);
WIRE 16 -1 (3525 2725)(4150 2725);
WIRE 16 -1 (3525 1625)(4675 1625);
WIRE 16 -1 (3525 1675)(4675 1675);
WIRE 16 -1 (4675 1675)(4675 1625);
WIRE 16 -1 (3525 1725)(4675 1725);
WIRE 16 -1 (4675 1725)(4675 1675);
WIRE 16 -1 (3525 1775)(4675 1775);
WIRE 16 -1 (4675 1775)(4675 1725);
WIRE 16 -1 (3525 1825)(4675 1825);
WIRE 16 -1 (4675 1825)(4675 1775);
WIRE 16 -1 (3525 1875)(4675 1875);
WIRE 16 -1 (4675 1875)(4675 1825);
WIRE 16 -1 (4675 1975)(3525 1975);
WIRE 16 -1 (4675 1975)(4675 1875);
WIRE 16 -1 (3525 2025)(4675 2025);
WIRE 16 -1 (4675 2025)(4675 1975);
WIRE 16 -1 (4675 2075)(4675 2025);
WIRE 16 -1 (3525 2075)(4675 2075);
WIRE 16 -1 (5000 1475)(3525 1475);
WIRE 16 -1 (3525 1525)(5000 1525);
WIRE 16 -1 (5000 1525)(5000 1475);
WIRE 16 -1 (3775 3325)(3525 3325);
WIRE 16 -1 (3775 3275)(3525 3275);
WIRE 16 -1 (3775 3325)(3775 3275);
WIRE 16 -1 (3775 3225)(3525 3225);
WIRE 16 -1 (3775 3275)(3775 3225);
WIRE 16 -1 (3775 3175)(3525 3175);
WIRE 16 -1 (3775 3225)(3775 3175);
WIRE 16 -1 (3775 3125)(3525 3125);
WIRE 16 -1 (3775 3175)(3775 3125);
WIRE 16 -1 (3775 3075)(3525 3075);
WIRE 16 -1 (3775 3125)(3775 3075);
WIRE 16 -1 (3775 3025)(3525 3025);
WIRE 16 -1 (3775 3075)(3775 3025);
WIRE 16 -1 (3775 2975)(3525 2975);
WIRE 16 -1 (3775 3025)(3775 2975);
WIRE 16 -1 (3775 2925)(3525 2925);
WIRE 16 -1 (3775 2975)(3775 2925);
WIRE 16 -1 (3775 2825)(3525 2825);
WIRE 16 -1 (3775 2875)(3525 2875);
WIRE 16 -1 (3775 2925)(3775 2875);
WIRE 16 -1 (3775 2875)(3775 2825);
WIRE 16 -1 (3525 1375)(5300 1375);
DOT 1 (-75 2875);
DOT 1 (3775 3175);
DOT 1 (3775 3225);
DOT 1 (3775 2875);
DOT 1 (4150 2725);
DOT 1 (4450 2225);
DOT 1 (4675 1775);
DOT 1 (4675 1825);
DOT 1 (4675 1725);
DOT 1 (4675 1675);
DOT 1 (-400 1925);
DOT 1 (-400 1825);
DOT 1 (-75 2325);
DOT 1 (-75 2175);
DOT 1 (-75 2125);
DOT 1 (3775 3125);
DOT 1 (-400 1575);
DOT 1 (-400 1775);
DOT 1 (-75 2475);
DOT 1 (-400 1675);
DOT 1 (-400 1625);
DOT 1 (-400 1475);
DOT 1 (-400 1425);
DOT 1 (-75 2225);
DOT 1 (-75 2675);
DOT 1 (-75 3225);
DOT 1 (-75 3125);
DOT 1 (-75 3175);
DOT 1 (-75 3075);
DOT 1 (-75 3025);
DOT 1 (-75 2975);
DOT 1 (-75 2925);
DOT 1 (-75 2775);
DOT 1 (-75 2725);
DOT 1 (-75 2275);
DOT 1 (-75 2425);
DOT 1 (-75 2525);
DOT 1 (-75 2575);
DOT 1 (-75 3325);
DOT 1 (3775 2925);
DOT 1 (3775 3025);
DOT 1 (3775 2975);
DOT 1 (3775 3075);
DOT 1 (3775 3275);
DOT 1 (3775 3325);
DOT 1 (5000 1525);
DOT 1 (4675 2025);
DOT 1 (4450 2425);
DOT 1 (4150 2575);
DOT 1 (4150 2625);
DOT 1 (4150 2675);
DOT 1 (4450 2325);
DOT 1 (4450 2375);
DOT 1 (4450 2275);
DOT 1 (4675 2075);
DOT 1 (4675 1975);
DOT 1 (4675 1875);
QUIT
